# S9S_MB_2U (Grand Teton) — schematic netlist excerpt (pin names and nets, part order shuffled) for the footprints in the layout excerpt that follows; sources: Cadence DE-HDL packaged netlist, KiCad conversion of 03242023_DA0F0TMBIJ0_F0T_Motherboard_J_brd_V01_OCP.brd

Q141  BC847BPN  IC  pkg SOT363XB  page 123
  E1  = GND
  B1  = H_CPU0_MEMTRIP_R
  C2  = H_CPU0_MEMTRIP
  E2  = PVNN_TERM_CPU0
  B2  = H_CPU0_MEMTRIP_OUT_VT_R_N
  C1  = H_CPU0_MEMTRIP_VT_N

Q69  MOSFET_NCH_DUAL  PJT138K IC  pkg SOT363XD  page 148
  S1  = GND
  G1  = RST_BMC_FROM_SWB_N
  D2  = RST_BMC_FROM_SWB_ISO_N
  S2  = GND
  G2  = RST_BMC_FROM_SWB
  D1  = RST_BMC_FROM_SWB

(kicad_pcb
	(version 20260206)
	(generator "pcbnew")
	(generator_version "10.0")
	(general
		(thickness 1.6)
		(legacy_teardrops no)
	)
	(paper "A4")
	(title_block
		(title "03242023_DA0F0TMBIJ0_F0T_Motherboard_J_brd_V01_OCP.brd")
		(comment 1 "Grand Teton / footprints 2463-2464 of 6105")
	)
	(layers
		(0 "F.Cu" signal "TOP")
		(4 "In1.Cu" signal "GND")
		(6 "In2.Cu" signal "IN1")
		(8 "In3.Cu" signal "GND1")
		(10 "In4.Cu" signal "IN2")
		(12 "In5.Cu" signal "GND2")
		(14 "In6.Cu" signal "IN3")
		(16 "In7.Cu" signal "GND3")
		(18 "In8.Cu" signal "VCC")
		(20 "In9.Cu" signal "VCC1")
		(22 "In10.Cu" signal "GND4")
		(24 "In11.Cu" signal "IN4")
		(26 "In12.Cu" signal "GND5")
		(28 "In13.Cu" signal "IN5")
		(30 "In14.Cu" signal "GND6")
		(32 "In15.Cu" signal "IN6")
		(34 "In16.Cu" signal "GND7")
		(2 "B.Cu" signal "BOTTOM")
		(9 "F.Adhes" user "F.Adhesive")
		(11 "B.Adhes" user "B.Adhesive")
		(13 "F.Paste" user "Package Geometry/Pastemask Top")
		(15 "B.Paste" user "Package Geometry/Pastemask Bottom")
		(5 "F.SilkS" user "Ref Des/Silkscreen Top")
		(7 "B.SilkS" user "Ref Des/Silkscreen Bottom")
		(1 "F.Mask" user "Board Geometry/Soldermask Top")
		(3 "B.Mask" user "Board Geometry/Soldermask Bottom")
		(17 "Dwgs.User" user "User.Drawings")
		(19 "Cmts.User" user "User.Comments")
		(21 "Eco1.User" user "User.Eco1")
		(23 "Eco2.User" user "User.Eco2")
		(25 "Edge.Cuts" user "Board Geometry/Outline")
		(27 "Margin" user)
		(31 "F.CrtYd" user "Package Geometry/Place Bound Top")
		(29 "B.CrtYd" user "Package Geometry/Place Bound Bottom")
		(35 "F.Fab" user "Ref Des/Assembly Top")
		(33 "B.Fab" user "Ref Des/Assembly Bottom")
	)
	(footprint ""
		(layer "F.Cu")
		(at 428.179992 -381.218948)
		(property "Reference" "Q69"
			(at 0.610108 -2.01803 0)
			(unlocked yes)
			(layer "F.SilkS")
			(effects
				(font
					(size 0.7874 0.5842)
					(thickness 0.1524)
				)
				(justify left)
			)
		)
		(property "Value" ""
			(at 0 0 0)
			(layer "F.Fab")
			(effects
				(font
					(size 1.27 1.27)
				)
			)
		)
		(duplicate_pad_numbers_are_jumpers no)
		(fp_line
			(start -1.332738 -1.100074)
			(end -0.4826 -1.100074)
			(stroke
				(width 0.1524)
				(type default)
			)
			(layer "F.SilkS")
		)
		(fp_line
			(start -1.332738 1.100074)
			(end -1.332738 -1.100074)
			(stroke
				(width 0.1524)
				(type default)
			)
			(layer "F.SilkS")
		)
		(fp_line
			(start -0.4826 -1.100074)
			(end 0 -0.541274)
			(stroke
				(width 0.1524)
				(type default)
			)
			(layer "F.SilkS")
		)
		(fp_line
			(start 0 -0.541274)
			(end 0.4826 -1.100074)
			(stroke
				(width 0.1524)
				(type default)
			)
			(layer "F.SilkS")
		)
		(fp_line
			(start 0.4826 -1.100074)
			(end 1.332738 -1.100074)
			(stroke
				(width 0.1524)
				(type default)
			)
			(layer "F.SilkS")
		)
		(fp_line
			(start 1.332738 -1.100074)
			(end 1.332738 1.100074)
			(stroke
				(width 0.1524)
				(type default)
			)
			(layer "F.SilkS")
		)
		(fp_line
			(start 1.332738 1.100074)
			(end -1.332738 1.100074)
			(stroke
				(width 0.1524)
				(type default)
			)
			(layer "F.SilkS")
		)
		(fp_poly
			(pts
				(xy -0.552958 -2.070608) (xy -0.903986 -1.368552) (xy -1.255014 -2.070608)
			)
			(stroke
				(width 0)
				(type default)
			)
			(fill yes)
			(layer "F.SilkS")
		)
		(fp_line
			(start -0.674878 -1.100074)
			(end 0.674878 -1.100074)
			(stroke
				(width 0.1)
				(type default)
			)
			(layer "F.Fab")
		)
		(fp_line
			(start -0.674878 1.100074)
			(end -0.674878 -1.100074)
			(stroke
				(width 0.1)
				(type default)
			)
			(layer "F.Fab")
		)
		(fp_line
			(start 0.674878 -1.100074)
			(end 0.674878 1.100074)
			(stroke
				(width 0.1)
				(type default)
			)
			(layer "F.Fab")
		)
		(fp_line
			(start 0.674878 1.100074)
			(end -0.674878 1.100074)
			(stroke
				(width 0.1)
				(type default)
			)
			(layer "F.Fab")
		)
		(fp_poly
			(pts
				(xy -2.2352 -0.298958) (xy -2.2352 -1.001014) (xy -1.533144 -0.649986)
			)
			(stroke
				(width 0)
				(type default)
			)
			(fill yes)
			(layer "F.Fab")
		)
		(pad "1" smd rect
			(at -0.94996 -0.649986 90)
			(size 0.4318 0.508)
			(layers "F.Cu" "F.Mask" "F.Paste")
			(net "GND")
		)
		(pad "2" smd rect
			(at -0.94996 0 90)
			(size 0.4318 0.508)
			(layers "F.Cu" "F.Mask" "F.Paste")
			(net "RST_BMC_FROM_SWB_N")
		)
		(pad "3" smd rect
			(at -0.94996 0.649986 90)
			(size 0.4318 0.508)
			(layers "F.Cu" "F.Mask" "F.Paste")
			(net "RST_BMC_FROM_SWB_ISO_N")
		)
		(pad "4" smd rect
			(at 0.94996 0.649986 90)
			(size 0.4318 0.508)
			(layers "F.Cu" "F.Mask" "F.Paste")
			(net "GND")
		)
		(pad "5" smd rect
			(at 0.94996 0 90)
			(size 0.4318 0.508)
			(layers "F.Cu" "F.Mask" "F.Paste")
			(net "RST_BMC_FROM_SWB")
		)
		(pad "6" smd rect
			(at 0.94996 -0.649986 90)
			(size 0.4318 0.508)
			(layers "F.Cu" "F.Mask" "F.Paste")
			(net "RST_BMC_FROM_SWB")
		)
	)
	(footprint ""
		(layer "F.Cu")
		(at 129.59588 -103.723948 -90)
		(property "Reference" "Q141"
			(at -0.162052 -2.00279 90)
			(unlocked yes)
			(layer "F.SilkS")
			(effects
				(font
					(size 0.7874 0.5842)
					(thickness 0.1524)
				)
			)
		)
		(property "Value" ""
			(at 0 0 270)
			(layer "F.Fab")
			(effects
				(font
					(size 1.27 1.27)
				)
			)
		)
		(duplicate_pad_numbers_are_jumpers no)
		(fp_line
			(start -1.376172 1.199896)
			(end -1.376172 -1.199896)
			(stroke
				(width 0.1524)
				(type default)
			)
			(layer "F.SilkS")
		)
		(fp_line
			(start 1.376172 1.199896)
			(end -1.376172 1.199896)
			(stroke
				(width 0.1524)
				(type default)
			)
			(layer "F.SilkS")
		)
		(fp_line
			(start 0 -0.762)
			(end 0.508 -1.199896)
			(stroke
				(width 0.1524)
				(type default)
			)
			(layer "F.SilkS")
		)
		(fp_line
			(start -1.376172 -1.199896)
			(end -0.508 -1.199896)
			(stroke
				(width 0.1524)
				(type default)
			)
			(layer "F.SilkS")
		)
		(fp_line
			(start -0.508 -1.199896)
			(end 0 -0.762)
			(stroke
				(width 0.1524)
				(type default)
			)
			(layer "F.SilkS")
		)
		(fp_line
			(start 0.508 -1.199896)
			(end 1.376172 -1.199896)
			(stroke
				(width 0.1524)
				(type default)
			)
			(layer "F.SilkS")
		)
		(fp_line
			(start 1.376172 -1.199896)
			(end 1.376172 1.199896)
			(stroke
				(width 0.1524)
				(type default)
			)
			(layer "F.SilkS")
		)
		(fp_poly
			(pts
				(xy -1.4605 -0.7493) (xy -2.2225 -1.1303) (xy -2.2225 -0.3683)
			)
			(stroke
				(width 0)
				(type default)
			)
			(fill yes)
			(layer "F.SilkS")
		)
		(fp_line
			(start -0.674878 1.100074)
			(end -0.674878 -1.100074)
			(stroke
				(width 0.1)
				(type default)
			)
			(layer "F.Fab")
		)
		(fp_line
			(start 0.674878 1.100074)
			(end -0.674878 1.100074)
			(stroke
				(width 0.1)
				(type default)
			)
			(layer "F.Fab")
		)
		(fp_line
			(start -0.674878 -1.100074)
			(end 0.674878 -1.100074)
			(stroke
				(width 0.1)
				(type default)
			)
			(layer "F.Fab")
		)
		(fp_line
			(start 0.674878 -1.100074)
			(end 0.674878 1.100074)
			(stroke
				(width 0.1)
				(type default)
			)
			(layer "F.Fab")
		)
		(fp_poly
			(pts
				(xy -1.4605 -0.7493) (xy -2.2225 -1.1303) (xy -2.2225 -0.3683)
			)
			(stroke
				(width 0)
				(type default)
			)
			(fill yes)
			(layer "F.Fab")
		)
		(pad "1" smd rect
			(at -0.899922 -0.750062 180)
			(size 0.6096 0.6096)
			(layers "F.Cu" "F.Mask" "F.Paste")
			(net "GND")
		)
		(pad "2" smd rect
			(at -0.899922 0 180)
			(size 0.4064 0.6096)
			(layers "F.Cu" "F.Mask" "F.Paste")
			(net "H_CPU0_MEMTRIP_R")
		)
		(pad "3" smd rect
			(at -0.899922 0.750062 180)
			(size 0.6096 0.6096)
			(layers "F.Cu" "F.Mask" "F.Paste")
			(net "H_CPU0_MEMTRIP")
		)
		(pad "4" smd rect
			(at 0.899922 0.750062 180)
			(size 0.6096 0.6096)
			(layers "F.Cu" "F.Mask" "F.Paste")
			(net "PVNN_TERM_CPU0")
		)
		(pad "5" smd rect
			(at 0.899922 0 180)
			(size 0.4064 0.6096)
			(layers "F.Cu" "F.Mask" "F.Paste")
			(net "H_CPU0_MEMTRIP_OUT_VT_R_N")
		)
		(pad "6" smd rect
			(at 0.899922 -0.750062 180)
			(size 0.6096 0.6096)
			(layers "F.Cu" "F.Mask" "F.Paste")
			(net "H_CPU0_MEMTRIP_VT_N")
		)
	)
)
